FILE_TYPE = CONNECTIVITY;
{Allegro Design Entry HDL 17.4-2019 S026 (4007227) 1/17/2022}
"PAGE_NUMBER" = 437;
0"NC";
1"P5E_CPU1_P0_TX_C_DN<7:0>";
2"P5E_CPU1_P0_TX_C_DP<7:0>";
3"P5E_CPU1_P0_TX_C_DP<15:8>";
4"P5E_CPU1_P0_TX_C_DN<15:8>";
5"P5E_CPU1_P0_TX_C_DN<13>";
6"P5E_CPU1_P0_TX_C_DP<13>";
7"P5E_CPU1_P0_TX_C_DP<15>";
8"P5E_CPU1_P0_TX_C_DP<14>";
9"P5E_CPU1_P0_TX_C_DN<15>";
10"P5E_CPU1_P0_TX_C_DN<14>";
11"P5E_CPU1_P0_TX_C_DN<9>";
12"P5E_CPU1_P0_TX_C_DN<10>";
13"P5E_CPU1_P0_TX_C_DN<11>";
14"P5E_CPU1_P0_TX_C_DN<12>";
15"P5E_CPU1_P0_TX_C_DN<8>";
16"P5E_CPU1_P0_TX_C_DP<1>";
17"P5E_CPU1_P0_TX_C_DN<1>";
18"P5E_CPU1_P0_TX_C_DP<2>";
19"P5E_CPU1_P0_TX_C_DN<0>";
20"P5E_CPU1_P0_TX_C_DP<0>";
21"P5E_CPU1_P0_TX_C_DN<2>";
22"P5E_CPU1_P0_TX_C_DN<7>";
23"P5E_CPU1_P0_TX_C_DP<9>";
24"P5E_CPU1_P0_TX_C_DP<5>";
25"P5E_CPU1_P0_TX_C_DN<5>";
26"P5E_CPU1_P0_TX_C_DP<12>";
27"P5E_CPU1_P0_TX_C_DP<10>";
28"P5E_CPU1_P0_TX_C_DP<11>";
29"P5E_CPU1_P0_TX_C_DP<8>";
30"P5E_CPU1_P0_TX_C_DP<3>";
31"P5E_CPU1_P0_TX_C_DP<7>";
32"P5E_CPU1_P0_TX_C_DP<6>";
33"P5E_CPU1_P0_TX_C_DN<6>";
34"P5E_CPU1_P0_TX_C_DN<4>";
35"P5E_CPU1_P0_TX_C_DP<4>";
36"P5E_CPU1_P0_TX_C_DN<3>";
%"PT5161LRS"
"8","(-7550,4100)","0","pure_quanta","I1";
;
LOCATION"U6014"
$SEC"8"
CDS_SEC"8"
PART_TYPE"SMLF"
VALUE"PT5161LRS"
MATERIAL"IC"
CDS_LIB"pure_quanta"
CDS_LMAN_SYM_OUTLINE"-350,1450,300,-1400"
NEEDS_NO_SIZE"TRUE"
PART_NUMBER"AJ051610U03";
"B_PERN7"
$PN"CD35"29;
"B_PERP7"
$PN"CB34"15;
"B_PERN6"
$PN"BU35"23;
"B_PERP6"
$PN"BR34"11;
"B_PERN5"
$PN"BK35"27;
"B_PERP5"
$PN"BH34"12;
"B_PERN4"
$PN"BC35"28;
"B_PERP4"
$PN"BA34"13;
"B_PERN3"
$PN"AT35"26;
"B_PERP3"
$PN"AP34"14;
"B_PERN2"
$PN"AJ35"5;
"B_PERP2"
$PN"AG34"6;
"B_PERN1"
$PN"AB35"8;
"B_PERP1"
$PN"Y34"10;
"B_PERN0"
$PN"R35"7;
"B_PERP0"
$PN"N34"9;
%"TAP"
"1","(-6525,4300)","0","standard","I10";
;
CDS_LIB"standard"
BODY_TYPE"PLUMBING"
HDL_TAP"TRUE";
"B \NAC \NWC"4;
"S \NAC"
BN"12"14;
%"TAP"
"1","(-6325,4200)","0","standard","I11";
;
CDS_LIB"standard"
BODY_TYPE"PLUMBING"
HDL_TAP"TRUE";
"B \NAC \NWC"3;
"S \NAC"
BN"12"26;
%"TAP"
"1","(-6525,4550)","0","standard","I12";
;
CDS_LIB"standard"
BODY_TYPE"PLUMBING"
HDL_TAP"TRUE";
"B \NAC \NWC"4;
"S \NAC"
BN"13"5;
%"TAP"
"1","(-6325,4650)","0","standard","I13";
;
CDS_LIB"standard"
BODY_TYPE"PLUMBING"
HDL_TAP"TRUE";
"B \NAC \NWC"3;
"S \NAC"
BN"13"6;
%"TAP"
"1","(-6325,4900)","0","standard","I14";
;
CDS_LIB"standard"
BODY_TYPE"PLUMBING"
HDL_TAP"TRUE";
"B \NAC \NWC"3;
"S \NAC"
BN"14"8;
%"TAP"
"1","(-6525,5000)","0","standard","I15";
;
CDS_LIB"standard"
BODY_TYPE"PLUMBING"
HDL_TAP"TRUE";
"B \NAC \NWC"4;
"S \NAC"
BN"14"10;
%"TAP"
"1","(-6525,5350)","0","standard","I16";
;
CDS_LIB"standard"
BODY_TYPE"PLUMBING"
HDL_TAP"TRUE";
"B \NAC \NWC"4;
"S \NAC"
BN"15"9;
%"TAP"
"1","(-6325,5250)","0","standard","I17";
;
CDS_LIB"standard"
BODY_TYPE"PLUMBING"
HDL_TAP"TRUE";
"B \NAC \NWC"3;
"S \NAC"
BN"15"7;
%"TAP"
"1","(-6325,2800)","0","standard","I2";
;
CDS_LIB"standard"
BODY_TYPE"PLUMBING"
HDL_TAP"TRUE";
"B \NAC \NWC"3;
"S \NAC"
BN"8"29;
%"TAP"
"1","(-1900,2850)","0","standard","I20";
;
CDS_LIB"standard"
BODY_TYPE"PLUMBING"
HDL_TAP"TRUE";
"B \NAC \NWC"1;
"S \NAC"
BN"0"19;
%"TAP"
"1","(-1700,2750)","0","standard","I21";
;
CDS_LIB"standard"
BODY_TYPE"PLUMBING"
HDL_TAP"TRUE";
"B \NAC \NWC"2;
"S \NAC"
BN"0"20;
%"TAP"
"1","(-1900,3100)","0","standard","I22";
;
CDS_LIB"standard"
BODY_TYPE"PLUMBING"
HDL_TAP"TRUE";
"B \NAC \NWC"1;
"S \NAC"
BN"1"17;
%"TAP"
"1","(-1700,3200)","0","standard","I23";
;
CDS_LIB"standard"
BODY_TYPE"PLUMBING"
HDL_TAP"TRUE";
"B \NAC \NWC"2;
"S \NAC"
BN"1"16;
%"TAP"
"1","(-1900,3550)","0","standard","I24";
;
CDS_LIB"standard"
BODY_TYPE"PLUMBING"
HDL_TAP"TRUE";
"B \NAC \NWC"1;
"S \NAC"
BN"2"21;
%"TAP"
"1","(-1900,3900)","0","standard","I25";
;
CDS_LIB"standard"
BODY_TYPE"PLUMBING"
HDL_TAP"TRUE";
"B \NAC \NWC"1;
"S \NAC"
BN"3"36;
%"TAP"
"1","(-1700,3450)","0","standard","I26";
;
CDS_LIB"standard"
BODY_TYPE"PLUMBING"
HDL_TAP"TRUE";
"B \NAC \NWC"2;
"S \NAC"
BN"2"18;
%"TAP"
"1","(-1700,3800)","0","standard","I27";
;
CDS_LIB"standard"
BODY_TYPE"PLUMBING"
HDL_TAP"TRUE";
"B \NAC \NWC"2;
"S \NAC"
BN"3"30;
%"TAP"
"1","(-1900,4250)","0","standard","I28";
;
CDS_LIB"standard"
BODY_TYPE"PLUMBING"
HDL_TAP"TRUE";
"B \NAC \NWC"1;
"S \NAC"
BN"4"34;
%"TAP"
"1","(-1700,4150)","0","standard","I29";
;
CDS_LIB"standard"
BODY_TYPE"PLUMBING"
HDL_TAP"TRUE";
"B \NAC \NWC"2;
"S \NAC"
BN"4"35;
%"TAP"
"1","(-6525,2900)","0","standard","I3";
;
CDS_LIB"standard"
BODY_TYPE"PLUMBING"
HDL_TAP"TRUE";
"B \NAC \NWC"4;
"S \NAC"
BN"8"15;
%"TAP"
"1","(-1900,4600)","0","standard","I30";
;
CDS_LIB"standard"
BODY_TYPE"PLUMBING"
HDL_TAP"TRUE";
"B \NAC \NWC"1;
"S \NAC"
BN"5"25;
%"TAP"
"1","(-1700,4500)","0","standard","I31";
;
CDS_LIB"standard"
BODY_TYPE"PLUMBING"
HDL_TAP"TRUE";
"B \NAC \NWC"2;
"S \NAC"
BN"5"24;
%"TAP"
"1","(-1700,4850)","0","standard","I32";
;
CDS_LIB"standard"
BODY_TYPE"PLUMBING"
HDL_TAP"TRUE";
"B \NAC \NWC"2;
"S \NAC"
BN"6"32;
%"TAP"
"1","(-1900,4950)","0","standard","I33";
;
CDS_LIB"standard"
BODY_TYPE"PLUMBING"
HDL_TAP"TRUE";
"B \NAC \NWC"1;
"S \NAC"
BN"6"33;
%"TAP"
"1","(-1900,5300)","0","standard","I34";
;
CDS_LIB"standard"
BODY_TYPE"PLUMBING"
HDL_TAP"TRUE";
"B \NAC \NWC"1;
"S \NAC"
BN"7"22;
%"TAP"
"1","(-1700,5200)","0","standard","I35";
;
CDS_LIB"standard"
BODY_TYPE"PLUMBING"
HDL_TAP"TRUE";
"B \NAC \NWC"2;
"S \NAC"
BN"7"31;
%"PT5161LRS"
"9","(-2925,4050)","0","pure_quanta","I38";
;
LOCATION"U6014"
$SEC"9"
CDS_SEC"9"
PART_TYPE"SMLF"
VALUE"PT5161LRS"
MATERIAL"IC"
NEEDS_NO_SIZE"TRUE"
CDS_LMAN_SYM_OUTLINE"-350,1450,300,-1400"
CDS_LIB"pure_quanta"
PART_NUMBER"AJ051610U03";
"B_PERN15"
$PN"EY35"20;
"B_PERP15"
$PN"EV34"19;
"B_PERN14"
$PN"EN35"17;
"B_PERP14"
$PN"EL34"16;
"B_PERN13"
$PN"EF35"18;
"B_PERP13"
$PN"ED34"21;
"B_PERN12"
$PN"DW35"30;
"B_PERP12"
$PN"DU34"36;
"B_PERN11"
$PN"DM35"35;
"B_PERP11"
$PN"DK34"34;
"B_PERN10"
$PN"DE35"24;
"B_PERP10"
$PN"DC34"25;
"B_PERN9"
$PN"CV35"32;
"B_PERP9"
$PN"CT34"33;
"B_PERN8"
$PN"CL35"31;
"B_PERP8"
$PN"CJ34"22;
%"TAP"
"1","(-6525,3250)","0","standard","I4";
;
CDS_LIB"standard"
BODY_TYPE"PLUMBING"
HDL_TAP"TRUE";
"B \NAC \NWC"4;
"S \NAC"
BN"9"11;
%"TAP"
"1","(-6325,3150)","0","standard","I5";
;
CDS_LIB"standard"
BODY_TYPE"PLUMBING"
HDL_TAP"TRUE";
"B \NAC \NWC"3;
"S \NAC"
BN"9"23;
%"TAP"
"1","(-6525,3600)","0","standard","I6";
;
CDS_LIB"standard"
BODY_TYPE"PLUMBING"
HDL_TAP"TRUE";
"B \NAC \NWC"4;
"S \NAC"
BN"10"12;
%"TAP"
"1","(-6325,3500)","0","standard","I7";
;
CDS_LIB"standard"
BODY_TYPE"PLUMBING"
HDL_TAP"TRUE";
"B \NAC \NWC"3;
"S \NAC"
BN"10"27;
%"TAP"
"1","(-6325,3850)","0","standard","I8";
;
CDS_LIB"standard"
BODY_TYPE"PLUMBING"
HDL_TAP"TRUE";
"B \NAC \NWC"3;
"S \NAC"
BN"11"28;
%"TAP"
"1","(-6525,3950)","0","standard","I9";
;
CDS_LIB"standard"
BODY_TYPE"PLUMBING"
HDL_TAP"TRUE";
"B \NAC \NWC"4;
"S \NAC"
BN"11"13;
END.
